(kicad_pcb
	(version 20260206)
	(generator "pcbnew")
	(generator_version "10.0")
	(general
		(thickness 1.6)
		(legacy_teardrops no)
	)
	(paper "A4")
	(title_block
		(title "Bryce Canyon_R.DPB_16317-1_OCP.brd")
		(comment 1 "Bryce Canyon / footprints 409-416 of 2099")
	)
	(layers
		(0 "F.Cu" signal "TOP")
		(4 "In1.Cu" signal "L2GND")
		(6 "In2.Cu" signal "L3")
		(8 "In3.Cu" signal "L4VCC")
		(10 "In4.Cu" signal "L5VCC")
		(12 "In5.Cu" signal "L6")
		(14 "In6.Cu" signal "L7GND")
		(2 "B.Cu" signal "BOTTOM")
		(9 "F.Adhes" user "F.Adhesive")
		(11 "B.Adhes" user "B.Adhesive")
		(13 "F.Paste" user "Package Geometry/Pastemask Top")
		(15 "B.Paste" user "Package Geometry/Pastemask Bottom")
		(5 "F.SilkS" user "Ref Des/Silkscreen Top")
		(7 "B.SilkS" user "Ref Des/Silkscreen Bottom")
		(1 "F.Mask" user "Board Geometry/Soldermask Top")
		(3 "B.Mask" user "Board Geometry/Soldermask Bottom")
		(17 "Dwgs.User" user "User.Drawings")
		(19 "Cmts.User" user "User.Comments")
		(21 "Eco1.User" user "User.Eco1")
		(23 "Eco2.User" user "User.Eco2")
		(25 "Edge.Cuts" user "Board Geometry/Outline")
		(27 "Margin" user)
		(31 "F.CrtYd" user "Package Geometry/Place Bound Top")
		(29 "B.CrtYd" user "Package Geometry/Place Bound Bottom")
		(35 "F.Fab" user "Ref Des/Assembly Top")
		(33 "B.Fab" user "Ref Des/Assembly Bottom")
	)
	(footprint ""
		(layer "F.Cu")
		(at 117.856 -19.177)
		(property "Reference" "R699"
			(at 0 0 0)
			(layer "F.SilkS")
			(hide yes)
			(effects
				(font
					(size 1.27 1.27)
				)
			)
		)
		(property "Value" "1KR2F-3-GP"
			(at 0.064008 -3.993896 0)
			(unlocked yes)
			(layer "F.Fab")
			(hide yes)
			(effects
				(font
					(size 1.016 1.016)
					(thickness 0.1524)
				)
			)
		)
		(property "Device Type" "R402H16"
			(at 0.064008 -5.517896 0)
			(unlocked yes)
			(layer "F.Fab")
			(hide yes)
			(effects
				(font
					(size 1.016 1.016)
					(thickness 0.1524)
				)
			)
		)
		(duplicate_pad_numbers_are_jumpers no)
		(fp_line
			(start -0.508 -0.9398)
			(end -0.508 0.9398)
			(stroke
				(width 0.1524)
				(type default)
			)
			(layer "F.SilkS")
		)
		(fp_line
			(start 0.508 -0.9398)
			(end -0.508 -0.9398)
			(stroke
				(width 0.1524)
				(type default)
			)
			(layer "F.SilkS")
		)
		(fp_rect
			(start -0.508 0.9398)
			(end 0.508 -0.9398)
			(stroke
				(width 0)
				(type default)
			)
			(fill no)
			(layer "F.CrtYd")
		)
		(fp_rect
			(start -0.508 0.9398)
			(end 0.508 -0.9398)
			(stroke
				(width 0)
				(type default)
			)
			(fill no)
			(layer "F.Fab")
		)
		(pad "1" smd custom
			(at 0 -0.4445)
			(size 0.1397 0.1397)
			(layers "F.Cu" "F.Mask" "F.Paste")
			(net "P3V3_STBY_B")
			(options
				(clearance outline)
				(anchor circle)
			)
			(primitives
				(gr_poly
					(pts
						(arc
							(start -0.1778 -0.2794)
							(mid -0.249642 -0.249642)
							(end -0.2794 -0.1778)
						)
						(arc
							(start -0.2794 0.1778)
							(mid -0.249642 0.249642)
							(end -0.1778 0.2794)
						)
						(arc
							(start 0.1778 0.2794)
							(mid 0.249642 0.249642)
							(end 0.2794 0.1778)
						)
						(arc
							(start 0.2794 -0.1778)
							(mid 0.249642 -0.249642)
							(end 0.1778 -0.2794)
						)
					)
					(width 0)
					(fill yes)
				)
			)
		)
		(pad "2" smd custom
			(at 0 0.4445)
			(size 0.1397 0.1397)
			(layers "F.Cu" "F.Mask" "F.Paste")
			(net "SW_PWR_R_HDD27")
			(options
				(clearance outline)
				(anchor circle)
			)
			(primitives
				(gr_poly
					(pts
						(arc
							(start -0.1778 -0.2794)
							(mid -0.249642 -0.249642)
							(end -0.2794 -0.1778)
						)
						(arc
							(start -0.2794 0.1778)
							(mid -0.249642 0.249642)
							(end -0.1778 0.2794)
						)
						(arc
							(start 0.1778 0.2794)
							(mid 0.249642 0.249642)
							(end 0.2794 0.1778)
						)
						(arc
							(start 0.2794 -0.1778)
							(mid 0.249642 -0.249642)
							(end 0.1778 -0.2794)
						)
					)
					(width 0)
					(fill yes)
				)
			)
		)
	)
	(footprint ""
		(layer "F.Cu")
		(at 426.974 -36.83 180)
		(property "Reference" "C460"
			(at 0 0 180)
			(layer "F.SilkS")
			(hide yes)
			(effects
				(font
					(size 1.27 1.27)
				)
			)
		)
		(property "Value" "SC10U16V6KX-2GP"
			(at -0.0762 -5.1308 180)
			(unlocked yes)
			(layer "F.Fab")
			(hide yes)
			(effects
				(font
					(size 1.016 1.016)
					(thickness 0.1524)
				)
			)
		)
		(property "Device Type" "C1206H71"
			(at -0.127 -6.6548 180)
			(unlocked yes)
			(layer "F.Fab")
			(hide yes)
			(effects
				(font
					(size 1.016 1.016)
					(thickness 0.1524)
				)
			)
		)
		(duplicate_pad_numbers_are_jumpers no)
		(fp_line
			(start 1.016 2.2352)
			(end -1.016 2.2352)
			(stroke
				(width 0.1524)
				(type default)
			)
			(layer "F.SilkS")
		)
		(fp_line
			(start 1.016 0.8382)
			(end 1.016 2.2352)
			(stroke
				(width 0.1524)
				(type default)
			)
			(layer "F.SilkS")
		)
		(fp_line
			(start 1.016 -2.2352)
			(end 1.016 -0.8382)
			(stroke
				(width 0.1524)
				(type default)
			)
			(layer "F.SilkS")
		)
		(fp_line
			(start -1.016 2.2352)
			(end -1.016 0.8382)
			(stroke
				(width 0.1524)
				(type default)
			)
			(layer "F.SilkS")
		)
		(fp_line
			(start -1.016 -0.8382)
			(end -1.016 -2.2352)
			(stroke
				(width 0.1524)
				(type default)
			)
			(layer "F.SilkS")
		)
		(fp_line
			(start -1.016 -2.2352)
			(end 1.016 -2.2352)
			(stroke
				(width 0.1524)
				(type default)
			)
			(layer "F.SilkS")
		)
		(fp_rect
			(start -1.0922 2.3114)
			(end 1.0922 -2.3114)
			(stroke
				(width 0)
				(type default)
			)
			(fill no)
			(layer "F.CrtYd")
		)
		(fp_poly
			(pts
				(xy 1.0922 -2.3114) (xy 1.0922 2.3114) (xy -1.0922 2.3114) (xy -1.0922 -2.3114)
			)
			(stroke
				(width 0)
				(type default)
			)
			(fill no)
			(layer "F.Fab")
		)
		(pad "1" smd rect
			(at 0 -1.397 180)
			(size 1.651 1.27)
			(layers "F.Cu" "F.Mask" "F.Paste")
			(net "P5V_HDD33")
		)
		(pad "2" smd rect
			(at 0 1.397 180)
			(size 1.651 1.27)
			(layers "F.Cu" "F.Mask" "F.Paste")
			(net "GND")
		)
	)
	(footprint ""
		(layer "F.Cu")
		(at 254.585978 -229.38105 90)
		(property "Reference" "R122"
			(at 0 0 90)
			(layer "F.SilkS")
			(hide yes)
			(effects
				(font
					(size 1.27 1.27)
				)
			)
		)
		(property "Value" "16K2R2F-GP"
			(at 0.064008 -3.993896 90)
			(unlocked yes)
			(layer "F.Fab")
			(hide yes)
			(effects
				(font
					(size 1.016 1.016)
					(thickness 0.1524)
				)
			)
		)
		(property "Device Type" "R402H16"
			(at 0.064008 -5.517896 90)
			(unlocked yes)
			(layer "F.Fab")
			(hide yes)
			(effects
				(font
					(size 1.016 1.016)
					(thickness 0.1524)
				)
			)
		)
		(duplicate_pad_numbers_are_jumpers no)
		(fp_line
			(start 0.508 -0.9398)
			(end -0.508 -0.9398)
			(stroke
				(width 0.1524)
				(type default)
			)
			(layer "F.SilkS")
		)
		(fp_line
			(start -0.508 -0.9398)
			(end -0.508 0.9398)
			(stroke
				(width 0.1524)
				(type default)
			)
			(layer "F.SilkS")
		)
		(fp_rect
			(start -0.508 0.9398)
			(end 0.508 -0.9398)
			(stroke
				(width 0)
				(type default)
			)
			(fill no)
			(layer "F.CrtYd")
		)
		(fp_rect
			(start -0.508 0.9398)
			(end 0.508 -0.9398)
			(stroke
				(width 0)
				(type default)
			)
			(fill no)
			(layer "F.Fab")
		)
		(pad "1" smd custom
			(at 0 -0.4445 90)
			(size 0.1397 0.1397)
			(layers "F.Cu" "F.Mask" "F.Paste")
			(net "P5V_B_1")
			(options
				(clearance outline)
				(anchor circle)
			)
			(primitives
				(gr_poly
					(pts
						(arc
							(start -0.1778 -0.2794)
							(mid -0.249642 -0.249642)
							(end -0.2794 -0.1778)
						)
						(arc
							(start -0.2794 0.1778)
							(mid -0.249642 0.249642)
							(end -0.1778 0.2794)
						)
						(arc
							(start 0.1778 0.2794)
							(mid 0.249642 0.249642)
							(end 0.2794 0.1778)
						)
						(arc
							(start 0.2794 -0.1778)
							(mid 0.249642 -0.249642)
							(end 0.1778 -0.2794)
						)
					)
					(width 0)
					(fill yes)
				)
			)
		)
		(pad "2" smd custom
			(at 0 0.4445 90)
			(size 0.1397 0.1397)
			(layers "F.Cu" "F.Mask" "F.Paste")
			(net "P5V_B_1_SENSE")
			(options
				(clearance outline)
				(anchor circle)
			)
			(primitives
				(gr_poly
					(pts
						(arc
							(start -0.1778 -0.2794)
							(mid -0.249642 -0.249642)
							(end -0.2794 -0.1778)
						)
						(arc
							(start -0.2794 0.1778)
							(mid -0.249642 0.249642)
							(end -0.1778 0.2794)
						)
						(arc
							(start 0.1778 0.2794)
							(mid 0.249642 0.249642)
							(end 0.2794 0.1778)
						)
						(arc
							(start 0.2794 -0.1778)
							(mid 0.249642 -0.249642)
							(end 0.1778 -0.2794)
						)
					)
					(width 0)
					(fill yes)
				)
			)
		)
	)
	(footprint ""
		(layer "F.Cu")
		(at 261.224522 -363.575346 90)
		(property "Reference" "R1033"
			(at 0 0 90)
			(layer "F.SilkS")
			(hide yes)
			(effects
				(font
					(size 1.27 1.27)
				)
			)
		)
		(property "Value" "0R0603-PAD-2-GP-U"
			(at 2.1209 -0.1397 90)
			(unlocked yes)
			(layer "F.Fab")
			(hide yes)
			(effects
				(font
					(size 1.016 1.016)
					(thickness 0.1524)
				)
			)
		)
		(property "Device Type" "0R0603-PAD-1-U"
			(at 2.1209 -1.6637 90)
			(unlocked yes)
			(layer "F.Fab")
			(hide yes)
			(effects
				(font
					(size 1.016 1.016)
					(thickness 0.1524)
				)
			)
		)
		(duplicate_pad_numbers_are_jumpers no)
		(fp_rect
			(start -0.5842 1.3335)
			(end 0.5842 -1.3335)
			(stroke
				(width 0)
				(type default)
			)
			(fill no)
			(layer "F.CrtYd")
		)
		(fp_rect
			(start -0.5842 1.3335)
			(end 0.5842 -1.3335)
			(stroke
				(width 0)
				(type default)
			)
			(fill no)
			(layer "F.Fab")
		)
		(pad "1" smd custom
			(at 0 -0.762 90)
			(size 0.2159 0.2159)
			(layers "F.Cu" "F.Mask" "F.Paste")
			(net "AGND_CURRENT_DPB")
			(options
				(clearance outline)
				(anchor circle)
			)
			(primitives
				(gr_poly
					(pts
						(arc
							(start -0.3302 -0.5842)
							(mid -0.402042 -0.554442)
							(end -0.4318 -0.4826)
						)
						(arc
							(start -0.4318 0.4826)
							(mid -0.402042 0.554442)
							(end -0.3302 0.5842)
						)
						(arc
							(start 0.3302 0.5842)
							(mid 0.402042 0.554442)
							(end 0.4318 0.4826)
						)
						(arc
							(start 0.4318 -0.4826)
							(mid 0.402042 -0.554442)
							(end 0.3302 -0.5842)
						)
					)
					(width 0)
					(fill yes)
				)
			)
		)
		(pad "2" smd custom
			(at 0 0.762 90)
			(size 0.2159 0.2159)
			(layers "F.Cu" "F.Mask" "F.Paste")
			(net "GND")
			(options
				(clearance outline)
				(anchor circle)
			)
			(primitives
				(gr_poly
					(pts
						(arc
							(start -0.4318 0.4826)
							(mid -0.402042 0.554442)
							(end -0.3302 0.5842)
						)
						(arc
							(start 0.3302 0.5842)
							(mid 0.402042 0.554442)
							(end 0.4318 0.4826)
						)
						(arc
							(start 0.4318 -0.4826)
							(mid 0.402042 -0.554442)
							(end 0.3302 -0.5842)
						)
						(arc
							(start -0.3302 -0.5842)
							(mid -0.402042 -0.554442)
							(end -0.4318 -0.4826)
						)
					)
					(width 0)
					(fill yes)
				)
			)
		)
	)
	(footprint ""
		(layer "F.Cu")
		(at 445.9859 -13.6271 180)
		(property "Reference" "VIA69"
			(at 0 0 180)
			(layer "F.SilkS")
			(hide yes)
			(effects
				(font
					(size 1.27 1.27)
				)
			)
		)
		(property "Value" "100OHM-8L-2D36MM-L18-GP"
			(at 3.8989 0.5715 180)
			(unlocked yes)
			(layer "F.Fab")
			(hide yes)
			(effects
				(font
					(size 1.016 1.016)
					(thickness 0.1524)
				)
			)
		)
		(property "Device Type" "VIA-PCIE-4P-414097"
			(at 3.8989 -0.9525 180)
			(unlocked yes)
			(layer "F.Fab")
			(hide yes)
			(effects
				(font
					(size 1.016 1.016)
					(thickness 0.1524)
				)
			)
		)
		(duplicate_pad_numbers_are_jumpers no)
		(fp_rect
			(start -2.0701 0.4826)
			(end 2.0701 -0.4826)
			(stroke
				(width 0)
				(type default)
			)
			(fill no)
			(layer "F.CrtYd")
		)
		(fp_rect
			(start -2.0701 0.4826)
			(end 2.0701 -0.4826)
			(stroke
				(width 0)
				(type default)
			)
			(fill no)
			(layer "F.Fab")
		)
		(pad "1" thru_hole circle
			(at -1.5875 0 180)
			(size 0.508 0.508)
			(drill 0.254)
			(layers "*.Cu" "*.Mask")
			(remove_unused_layers no)
			(net "GND")
			(clearance 0.2286)
			(thermal_gap 0.2286)
		)
		(pad "2" thru_hole circle
			(at -0.5715 0 180)
			(size 0.508 0.508)
			(drill 0.254)
			(layers "*.Cu" "*.Mask")
			(remove_unused_layers no)
			(net "PHY_SCC_B_TO_DRV_B_34_DP")
			(clearance 0.2286)
			(thermal_gap 0.2286)
		)
		(pad "3" thru_hole circle
			(at 0.5715 0 180)
			(size 0.508 0.508)
			(drill 0.254)
			(layers "*.Cu" "*.Mask")
			(remove_unused_layers no)
			(net "PHY_SCC_B_TO_DRV_B_34_DN")
			(clearance 0.2286)
			(thermal_gap 0.2286)
		)
		(pad "4" thru_hole circle
			(at 1.5875 0 180)
			(size 0.508 0.508)
			(drill 0.254)
			(layers "*.Cu" "*.Mask")
			(remove_unused_layers no)
			(net "GND")
			(clearance 0.2286)
			(thermal_gap 0.2286)
		)
	)
	(footprint ""
		(layer "F.Cu")
		(at 77.978 -254.508 -90)
		(property "Reference" "R201"
			(at 0 0 270)
			(layer "F.SilkS")
			(hide yes)
			(effects
				(font
					(size 1.27 1.27)
				)
			)
		)
		(property "Value" "300KR2F-GP"
			(at 0.064008 -3.993896 270)
			(unlocked yes)
			(layer "F.Fab")
			(hide yes)
			(effects
				(font
					(size 1.016 1.016)
					(thickness 0.1524)
				)
			)
		)
		(property "Device Type" "R402H16"
			(at 0.064008 -5.517896 270)
			(unlocked yes)
			(layer "F.Fab")
			(hide yes)
			(effects
				(font
					(size 1.016 1.016)
					(thickness 0.1524)
				)
			)
		)
		(duplicate_pad_numbers_are_jumpers no)
		(fp_line
			(start -0.508 -0.9398)
			(end -0.508 0.9398)
			(stroke
				(width 0.1524)
				(type default)
			)
			(layer "F.SilkS")
		)
		(fp_line
			(start 0.508 -0.9398)
			(end -0.508 -0.9398)
			(stroke
				(width 0.1524)
				(type default)
			)
			(layer "F.SilkS")
		)
		(fp_rect
			(start -0.508 0.9398)
			(end 0.508 -0.9398)
			(stroke
				(width 0)
				(type default)
			)
			(fill no)
			(layer "F.CrtYd")
		)
		(fp_rect
			(start -0.508 0.9398)
			(end 0.508 -0.9398)
			(stroke
				(width 0)
				(type default)
			)
			(fill no)
			(layer "F.Fab")
		)
		(pad "1" smd custom
			(at 0 -0.4445 270)
			(size 0.1397 0.1397)
			(layers "F.Cu" "F.Mask" "F.Paste")
			(net "SW_HDD_N2")
			(options
				(clearance outline)
				(anchor circle)
			)
			(primitives
				(gr_poly
					(pts
						(arc
							(start -0.1778 -0.2794)
							(mid -0.249642 -0.249642)
							(end -0.2794 -0.1778)
						)
						(arc
							(start -0.2794 0.1778)
							(mid -0.249642 0.249642)
							(end -0.1778 0.2794)
						)
						(arc
							(start 0.1778 0.2794)
							(mid 0.249642 0.249642)
							(end 0.2794 0.1778)
						)
						(arc
							(start 0.2794 -0.1778)
							(mid 0.249642 -0.249642)
							(end 0.1778 -0.2794)
						)
					)
					(width 0)
					(fill yes)
				)
			)
		)
		(pad "2" smd custom
			(at 0 0.4445 270)
			(size 0.1397 0.1397)
			(layers "F.Cu" "F.Mask" "F.Paste")
			(net "P12V_B")
			(options
				(clearance outline)
				(anchor circle)
			)
			(primitives
				(gr_poly
					(pts
						(arc
							(start -0.1778 -0.2794)
							(mid -0.249642 -0.249642)
							(end -0.2794 -0.1778)
						)
						(arc
							(start -0.2794 0.1778)
							(mid -0.249642 0.249642)
							(end -0.1778 0.2794)
						)
						(arc
							(start 0.1778 0.2794)
							(mid 0.249642 0.249642)
							(end 0.2794 0.1778)
						)
						(arc
							(start 0.2794 -0.1778)
							(mid 0.249642 -0.249642)
							(end 0.1778 -0.2794)
						)
					)
					(width 0)
					(fill yes)
				)
			)
		)
	)
	(footprint ""
		(layer "F.Cu")
		(at 180.848 -366.649 90)
		(property "Reference" "R993"
			(at 0 0 90)
			(layer "F.SilkS")
			(hide yes)
			(effects
				(font
					(size 1.27 1.27)
				)
			)
		)
		(property "Value" "0R2J-2-GP"
			(at 0.064008 -3.993896 90)
			(unlocked yes)
			(layer "F.Fab")
			(hide yes)
			(effects
				(font
					(size 1.016 1.016)
					(thickness 0.1524)
				)
			)
		)
		(property "Device Type" "R402H16"
			(at 0.064008 -5.517896 90)
			(unlocked yes)
			(layer "F.Fab")
			(hide yes)
			(effects
				(font
					(size 1.016 1.016)
					(thickness 0.1524)
				)
			)
		)
		(duplicate_pad_numbers_are_jumpers no)
		(fp_line
			(start 0.508 -0.9398)
			(end -0.508 -0.9398)
			(stroke
				(width 0.1524)
				(type default)
			)
			(layer "F.SilkS")
		)
		(fp_line
			(start -0.508 -0.9398)
			(end -0.508 0.9398)
			(stroke
				(width 0.1524)
				(type default)
			)
			(layer "F.SilkS")
		)
		(fp_rect
			(start -0.508 0.9398)
			(end 0.508 -0.9398)
			(stroke
				(width 0)
				(type default)
			)
			(fill no)
			(layer "F.CrtYd")
		)
		(fp_rect
			(start -0.508 0.9398)
			(end 0.508 -0.9398)
			(stroke
				(width 0)
				(type default)
			)
			(fill no)
			(layer "F.Fab")
		)
		(pad "1" smd custom
			(at 0 -0.4445 90)
			(size 0.1397 0.1397)
			(layers "F.Cu" "F.Mask" "F.Paste")
			(net "MB0_SPISS_PD")
			(options
				(clearance outline)
				(anchor circle)
			)
			(primitives
				(gr_poly
					(pts
						(arc
							(start -0.1778 -0.2794)
							(mid -0.249642 -0.249642)
							(end -0.2794 -0.1778)
						)
						(arc
							(start -0.2794 0.1778)
							(mid -0.249642 0.249642)
							(end -0.1778 0.2794)
						)
						(arc
							(start 0.1778 0.2794)
							(mid 0.249642 0.249642)
							(end 0.2794 0.1778)
						)
						(arc
							(start 0.2794 -0.1778)
							(mid 0.249642 -0.249642)
							(end 0.1778 -0.2794)
						)
					)
					(width 0)
					(fill yes)
				)
			)
		)
		(pad "2" smd custom
			(at 0 0.4445 90)
			(size 0.1397 0.1397)
			(layers "F.Cu" "F.Mask" "F.Paste")
			(net "AGND_CURRENT_MON")
			(options
				(clearance outline)
				(anchor circle)
			)
			(primitives
				(gr_poly
					(pts
						(arc
							(start -0.1778 -0.2794)
							(mid -0.249642 -0.249642)
							(end -0.2794 -0.1778)
						)
						(arc
							(start -0.2794 0.1778)
							(mid -0.249642 0.249642)
							(end -0.1778 0.2794)
						)
						(arc
							(start 0.1778 0.2794)
							(mid 0.249642 0.249642)
							(end 0.2794 0.1778)
						)
						(arc
							(start 0.2794 -0.1778)
							(mid 0.249642 -0.249642)
							(end 0.1778 -0.2794)
						)
					)
					(width 0)
					(fill yes)
				)
			)
		)
	)
	(footprint ""
		(layer "F.Cu")
		(at 367.284 -128.651 180)
		(property "Reference" "R517"
			(at 0 0 180)
			(layer "F.SilkS")
			(hide yes)
			(effects
				(font
					(size 1.27 1.27)
				)
			)
		)
		(property "Value" "0R2J-2-GP"
			(at 0.064008 -3.993896 180)
			(unlocked yes)
			(layer "F.Fab")
			(hide yes)
			(effects
				(font
					(size 1.016 1.016)
					(thickness 0.1524)
				)
			)
		)
		(property "Device Type" "R402H16"
			(at 0.064008 -5.517896 180)
			(unlocked yes)
			(layer "F.Fab")
			(hide yes)
			(effects
				(font
					(size 1.016 1.016)
					(thickness 0.1524)
				)
			)
		)
		(duplicate_pad_numbers_are_jumpers no)
		(fp_line
			(start 0.508 -0.9398)
			(end -0.508 -0.9398)
			(stroke
				(width 0.1524)
				(type default)
			)
			(layer "F.SilkS")
		)
		(fp_line
			(start -0.508 -0.9398)
			(end -0.508 0.9398)
			(stroke
				(width 0.1524)
				(type default)
			)
			(layer "F.SilkS")
		)
		(fp_rect
			(start -0.508 0.9398)
			(end 0.508 -0.9398)
			(stroke
				(width 0)
				(type default)
			)
			(fill no)
			(layer "F.CrtYd")
		)
		(fp_rect
			(start -0.508 0.9398)
			(end 0.508 -0.9398)
			(stroke
				(width 0)
				(type default)
			)
			(fill no)
			(layer "F.Fab")
		)
		(pad "1" smd custom
			(at 0 -0.4445 180)
			(size 0.1397 0.1397)
			(layers "F.Cu" "F.Mask" "F.Paste")
			(net "DRIVE_B_19_PWR")
			(options
				(clearance outline)
				(anchor circle)
			)
			(primitives
				(gr_poly
					(pts
						(arc
							(start -0.1778 -0.2794)
							(mid -0.249642 -0.249642)
							(end -0.2794 -0.1778)
						)
						(arc
							(start -0.2794 0.1778)
							(mid -0.249642 0.249642)
							(end -0.1778 0.2794)
						)
						(arc
							(start 0.1778 0.2794)
							(mid 0.249642 0.249642)
							(end 0.2794 0.1778)
						)
						(arc
							(start 0.2794 -0.1778)
							(mid 0.249642 -0.249642)
							(end 0.1778 -0.2794)
						)
					)
					(width 0)
					(fill yes)
				)
			)
		)
		(pad "2" smd custom
			(at 0 0.4445 180)
			(size 0.1397 0.1397)
			(layers "F.Cu" "F.Mask" "F.Paste")
			(net "SW_PWR_R_HDD19")
			(options
				(clearance outline)
				(anchor circle)
			)
			(primitives
				(gr_poly
					(pts
						(arc
							(start -0.1778 -0.2794)
							(mid -0.249642 -0.249642)
							(end -0.2794 -0.1778)
						)
						(arc
							(start -0.2794 0.1778)
							(mid -0.249642 0.249642)
							(end -0.1778 0.2794)
						)
						(arc
							(start 0.1778 0.2794)
							(mid 0.249642 0.249642)
							(end 0.2794 0.1778)
						)
						(arc
							(start 0.2794 -0.1778)
							(mid 0.249642 -0.249642)
							(end 0.1778 -0.2794)
						)
					)
					(width 0)
					(fill yes)
				)
			)
		)
	)
)
